#ISCELL
  mstr_symbols cad_note *
  *
#ISCELL
  mstr_symbols intel_corp_bpage *
  *
#CELL
  mstr_discrete cap *
  page105_i1
#ISCELL
  mstr_standard tap *
  page105_i10
#ISCELL
  mstr_standard tap *
  page105_i11
#CELL
  mstr_discrete cap *
  page105_i12
#CELL
  mstr_discrete cap *
  page105_i13
#ISCELL
  mstr_standard tap *
  page105_i14
#ISCELL
  mstr_standard tap *
  page105_i15
#ISCELL
  mstr_standard tap *
  page105_i151
#ISCELL
  mstr_standard tap *
  page105_i152
#CELL
  mstr_discrete cap *
  page105_i153
#ISCELL
  mstr_standard tap *
  page105_i154
#ISCELL
  mstr_standard tap *
  page105_i155
#ISCELL
  mstr_standard tap *
  page105_i156
#ISCELL
  mstr_standard tap *
  page105_i157
#ISCELL
  mstr_standard tap *
  page105_i158
#ISCELL
  mstr_standard tap *
  page105_i159
#ISCELL
  mstr_standard tap *
  page105_i16
#CELL
  mstr_discrete cap *
  page105_i160
#ISCELL
  mstr_standard tap *
  page105_i161
#ISCELL
  mstr_standard tap *
  page105_i162
#CELL
  mstr_discrete cap *
  page105_i163
#ISCELL
  mstr_standard tap *
  page105_i164
#ISCELL
  mstr_standard tap *
  page105_i165
#CELL
  mstr_discrete cap *
  page105_i166
#ISCELL
  mstr_standard tap *
  page105_i167
#ISCELL
  mstr_standard tap *
  page105_i168
#CELL
  mstr_discrete cap *
  page105_i169
#ISCELL
  mstr_standard tap *
  page105_i17
#ISCELL
  mstr_standard tap *
  page105_i170
#ISCELL
  mstr_standard offpage *
  page105_i171
#ISCELL
  mstr_standard tap *
  page105_i172
#CELL
  mstr_discrete cap *
  page105_i173
#ISCELL
  mstr_standard tap *
  page105_i174
#CELL
  mstr_discrete cap *
  page105_i175
#ISCELL
  mstr_standard tap *
  page105_i176
#ISCELL
  mstr_standard tap *
  page105_i177
#ISCELL
  mstr_standard tap *
  page105_i178
#ISCELL
  mstr_standard tap *
  page105_i179
#ISCELL
  mstr_standard tap *
  page105_i18
#CELL
  mstr_discrete cap *
  page105_i180
#CELL
  mstr_discrete cap *
  page105_i181
#ISCELL
  mstr_standard tap *
  page105_i182
#ISCELL
  mstr_standard tap *
  page105_i183
#ISCELL
  mstr_standard tap *
  page105_i184
#CELL
  mstr_discrete cap *
  page105_i185
#ISCELL
  mstr_standard tap *
  page105_i186
#CELL
  mstr_discrete cap *
  page105_i187
#ISCELL
  mstr_standard tap *
  page105_i188
#CELL
  mstr_discrete cap *
  page105_i189
#ISCELL
  mstr_standard tap *
  page105_i19
#ISCELL
  mstr_standard tap *
  page105_i190
#ISCELL
  mstr_standard tap *
  page105_i191
#ISCELL
  mstr_standard tap *
  page105_i192
#CELL
  mstr_discrete cap *
  page105_i193
#ISCELL
  mstr_standard tap *
  page105_i194
#ISCELL
  mstr_standard tap *
  page105_i195
#CELL
  mstr_discrete cap *
  page105_i196
#ISCELL
  mstr_standard tap *
  page105_i197
#CELL
  mstr_discrete cap *
  page105_i198
#ISCELL
  mstr_standard offpage *
  page105_i199
#CELL
  mstr_discrete cap *
  page105_i20
#ISCELL
  mstr_standard tap *
  page105_i200
#CELL
  mstr_discrete cap *
  page105_i201
#ISCELL
  mstr_standard tap *
  page105_i202
#ISCELL
  mstr_standard offpage *
  page105_i203
#ISCELL
  mstr_standard offpage *
  page105_i204
#CELL
  mstr_discrete cap *
  page105_i205
#CELL
  mstr_discrete cap *
  page105_i206
#ISCELL
  mstr_standard offpage *
  page105_i207
#ISCELL
  mstr_standard offpage *
  page105_i208
#ISCELL
  mstr_standard tap *
  page105_i209
#CELL
  mstr_discrete cap *
  page105_i21
#ISCELL
  mstr_standard tap *
  page105_i210
#ISCELL
  mstr_standard tap *
  page105_i211
#CELL
  mstr_discrete cap *
  page105_i212
#ISCELL
  mstr_standard tap *
  page105_i213
#ISCELL
  mstr_standard tap *
  page105_i214
#ISCELL
  mstr_standard tap *
  page105_i215
#ISCELL
  mstr_standard tap *
  page105_i216
#CELL
  mstr_discrete cap *
  page105_i217
#CELL
  mstr_discrete cap *
  page105_i218
#ISCELL
  mstr_standard tap *
  page105_i219
#CELL
  mstr_discrete cap *
  page105_i22
#ISCELL
  mstr_standard tap *
  page105_i220
#ISCELL
  mstr_standard tap *
  page105_i221
#ISCELL
  mstr_standard tap *
  page105_i222
#CELL
  mstr_discrete cap *
  page105_i223
#ISCELL
  mstr_standard tap *
  page105_i224
#CELL
  mstr_discrete cap *
  page105_i225
#ISCELL
  mstr_standard tap *
  page105_i226
#ISCELL
  mstr_standard tap *
  page105_i227
#ISCELL
  mstr_standard tap *
  page105_i228
#CELL
  mstr_discrete cap *
  page105_i229
#ISCELL
  mstr_standard tap *
  page105_i23
#ISCELL
  mstr_standard tap *
  page105_i230
#ISCELL
  mstr_standard tap *
  page105_i231
#CELL
  mstr_discrete cap *
  page105_i232
#ISCELL
  mstr_standard tap *
  page105_i233
#CELL
  mstr_discrete cap *
  page105_i234
#ISCELL
  mstr_standard tap *
  page105_i235
#ISCELL
  mstr_standard tap *
  page105_i236
#ISCELL
  mstr_standard offpage *
  page105_i237
#ISCELL
  mstr_standard tap *
  page105_i238
#CELL
  mstr_discrete cap *
  page105_i239
#ISCELL
  mstr_standard tap *
  page105_i24
#ISCELL
  mstr_standard tap *
  page105_i240
#ISCELL
  mstr_standard tap *
  page105_i241
#ISCELL
  mstr_standard tap *
  page105_i242
#ISCELL
  mstr_standard tap *
  page105_i243
#CELL
  mstr_discrete cap *
  page105_i244
#ISCELL
  mstr_standard tap *
  page105_i245
#CELL
  mstr_discrete cap *
  page105_i246
#CELL
  mstr_discrete cap *
  page105_i247
#ISCELL
  mstr_standard tap *
  page105_i248
#ISCELL
  mstr_standard offpage *
  page105_i249
#ISCELL
  mstr_standard tap *
  page105_i25
#ISCELL
  mstr_standard tap *
  page105_i250
#ISCELL
  mstr_standard tap *
  page105_i251
#ISCELL
  mstr_standard tap *
  page105_i252
#CELL
  mstr_discrete cap *
  page105_i253
#ISCELL
  mstr_standard tap *
  page105_i254
#CELL
  mstr_discrete cap *
  page105_i255
#ISCELL
  mstr_standard tap *
  page105_i256
#ISCELL
  mstr_standard tap *
  page105_i26
#CELL
  mstr_discrete cap *
  page105_i27
#CELL
  mstr_discrete cap *
  page105_i28
#ISCELL
  mstr_standard tap *
  page105_i29
#ISCELL
  mstr_standard offpage *
  page105_i3
#ISCELL
  mstr_standard tap *
  page105_i30
#CELL
  mstr_discrete cap *
  page105_i31
#CELL
  mstr_discrete cap *
  page105_i32
#ISCELL
  mstr_standard tap *
  page105_i33
#CELL
  mstr_discrete cap *
  page105_i34
#ISCELL
  mstr_standard tap *
  page105_i35
#ISCELL
  mstr_standard tap *
  page105_i36
#CELL
  mstr_discrete cap *
  page105_i37
#ISCELL
  mstr_standard tap *
  page105_i38
#ISCELL
  mstr_standard tap *
  page105_i39
#ISCELL
  mstr_standard tap *
  page105_i4
#ISCELL
  mstr_standard tap *
  page105_i40
#ISCELL
  mstr_standard tap *
  page105_i41
#ISCELL
  mstr_standard tap *
  page105_i42
#ISCELL
  mstr_standard tap *
  page105_i43
#CELL
  mstr_discrete cap *
  page105_i44
#CELL
  mstr_discrete cap *
  page105_i45
#CELL
  mstr_discrete cap *
  page105_i46
#ISCELL
  mstr_standard tap *
  page105_i47
#ISCELL
  mstr_standard tap *
  page105_i48
#ISCELL
  mstr_standard tap *
  page105_i49
#ISCELL
  mstr_standard tap *
  page105_i5
#ISCELL
  mstr_standard tap *
  page105_i50
#CELL
  mstr_discrete cap *
  page105_i51
#CELL
  mstr_discrete cap *
  page105_i52
#ISCELL
  mstr_standard tap *
  page105_i53
#ISCELL
  mstr_standard tap *
  page105_i54
#CELL
  mstr_discrete cap *
  page105_i55
#CELL
  mstr_discrete cap *
  page105_i56
#ISCELL
  mstr_standard tap *
  page105_i57
#CELL
  mstr_discrete cap *
  page105_i58
#ISCELL
  mstr_standard tap *
  page105_i59
#CELL
  mstr_discrete cap *
  page105_i6
#ISCELL
  mstr_standard tap *
  page105_i60
#CELL
  mstr_discrete cap *
  page105_i61
#CELL
  mstr_discrete cap *
  page105_i62
#ISCELL
  mstr_standard tap *
  page105_i63
#ISCELL
  mstr_standard tap *
  page105_i64
#ISCELL
  mstr_standard tap *
  page105_i65
#ISCELL
  mstr_standard tap *
  page105_i66
#ISCELL
  mstr_standard tap *
  page105_i67
#ISCELL
  mstr_standard tap *
  page105_i68
#CELL
  mstr_discrete cap *
  page105_i69
#CELL
  mstr_discrete cap *
  page105_i7
#CELL
  mstr_discrete cap *
  page105_i70
#CELL
  mstr_discrete cap *
  page105_i71
#ISCELL
  mstr_standard tap *
  page105_i72
#ISCELL
  mstr_standard tap *
  page105_i73
#ISCELL
  mstr_standard tap *
  page105_i74
#CELL
  mstr_discrete cap *
  page105_i75
#CELL
  mstr_discrete cap *
  page105_i76
#ISCELL
  mstr_standard offpage *
  page105_i77
#ISCELL
  mstr_standard tap *
  page105_i78
#ISCELL
  mstr_standard tap *
  page105_i79
#CELL
  mstr_discrete cap *
  page105_i8
#ISCELL
  mstr_standard tap *
  page105_i80
#ISCELL
  mstr_standard tap *
  page105_i81
#ISCELL
  mstr_standard tap *
  page105_i82
#ISCELL
  mstr_standard tap *
  page105_i83
#ISCELL
  mstr_standard tap *
  page105_i84
#ISCELL
  mstr_standard tap *
  page105_i85
#ISCELL
  mstr_standard tap *
  page105_i86
#ISCELL
  mstr_standard tap *
  page105_i87
#ISCELL
  mstr_standard tap *
  page105_i88
#ISCELL
  mstr_standard tap *
  page105_i89
#ISCELL
  mstr_standard tap *
  page105_i9
#ISCELL
  mstr_standard tap *
  page105_i90
#ISCELL
  mstr_standard tap *
  page105_i91
#ISCELL
  mstr_standard tap *
  page105_i92
#CELL
  mstr_discrete cap *
  page105_i93
#ISCELL
  mstr_standard tap *
  page105_i94
#ISCELL
  mstr_standard offpage *
  page105_i95
#CELL
  mstr_discrete cap *
  page105_i96
#ISCELL
  mstr_standard tap *
  page105_i97
#ISCELL
  mstr_standard tap *
  page105_i98
#ISCELL
  mstr_standard offpage *
  page105_i99
